# SCM (Grand Teton) — schematic netlist excerpt (pin names and nets, part order shuffled) for the footprints in the layout excerpt that follows; sources: Cadence DE-HDL packaged netlist, KiCad conversion of 12092022_DA0F0TMDCD0_F0T_Management_Board_D_brd_V3_OCP.brd

R148  Q_RES  33.2 1% CHIP  pkg 0402LF  page 12 : A = SGPIO_CLK_1 ; B = SGPIO_BMC_M1_CLK

(kicad_pcb
	(version 20260206)
	(generator "pcbnew")
	(generator_version "10.0")
	(general
		(thickness 1.6)
		(legacy_teardrops no)
	)
	(paper "A4")
	(title_block
		(title "12092022_DA0F0TMDCD0_F0T_Management_Board_D_brd_V3_OCP.brd")
		(comment 1 "Grand Teton / footprints 614-614 of 1440")
	)
	(layers
		(0 "F.Cu" signal "TOP")
		(4 "In1.Cu" signal "GND")
		(6 "In2.Cu" signal "IN1")
		(8 "In3.Cu" signal "GND1")
		(10 "In4.Cu" signal "IN2")
		(12 "In5.Cu" signal "VCC")
		(14 "In6.Cu" signal "VCC1")
		(16 "In7.Cu" signal "IN3")
		(18 "In8.Cu" signal "GND2")
		(20 "In9.Cu" signal "IN4")
		(22 "In10.Cu" signal "GND3")
		(2 "B.Cu" signal "BOTTOM")
		(9 "F.Adhes" user "F.Adhesive")
		(11 "B.Adhes" user "B.Adhesive")
		(13 "F.Paste" user "Package Geometry/Pastemask Top")
		(15 "B.Paste" user "Package Geometry/Pastemask Bottom")
		(5 "F.SilkS" user "Ref Des/Silkscreen Top")
		(7 "B.SilkS" user "Ref Des/Silkscreen Bottom")
		(1 "F.Mask" user "Board Geometry/Soldermask Top")
		(3 "B.Mask" user "Board Geometry/Soldermask Bottom")
		(17 "Dwgs.User" user "User.Drawings")
		(19 "Cmts.User" user "User.Comments")
		(21 "Eco1.User" user "User.Eco1")
		(23 "Eco2.User" user "User.Eco2")
		(25 "Edge.Cuts" user "Board Geometry/Outline")
		(27 "Margin" user)
		(31 "F.CrtYd" user "Package Geometry/Place Bound Top")
		(29 "B.CrtYd" user "Package Geometry/Place Bound Bottom")
		(35 "F.Fab" user "Ref Des/Assembly Top")
		(33 "B.Fab" user "Ref Des/Assembly Bottom")
	)
	(footprint ""
		(layer "F.Cu")
		(at 50.79619 -34.637726 90)
		(property "Reference" "R148"
			(at 0 0 90)
			(layer "F.SilkS")
			(hide yes)
			(effects
				(font
					(size 1.27 1.27)
				)
			)
		)
		(property "Value" ""
			(at 0 0 90)
			(layer "F.Fab")
			(effects
				(font
					(size 1.27 1.27)
				)
			)
		)
		(duplicate_pad_numbers_are_jumpers no)
		(fp_line
			(start 0.7874 -0.4064)
			(end 0.7874 0.4064)
			(stroke
				(width 0.1524)
				(type default)
			)
			(layer "F.SilkS")
		)
		(fp_line
			(start -0.7874 -0.4064)
			(end 0.7874 -0.4064)
			(stroke
				(width 0.1524)
				(type default)
			)
			(layer "F.SilkS")
		)
		(fp_line
			(start 0.7874 0.4064)
			(end -0.7874 0.4064)
			(stroke
				(width 0.1524)
				(type default)
			)
			(layer "F.SilkS")
		)
		(fp_line
			(start -0.7874 0.4064)
			(end -0.7874 -0.4064)
			(stroke
				(width 0.1524)
				(type default)
			)
			(layer "F.SilkS")
		)
		(fp_line
			(start -0.12065 -0.305054)
			(end -0.12065 -0.2794)
			(stroke
				(width 0.1)
				(type default)
			)
			(layer "F.Fab")
		)
		(fp_line
			(start -0.67945 -0.305054)
			(end -0.12065 -0.305054)
			(stroke
				(width 0.1)
				(type default)
			)
			(layer "F.Fab")
		)
		(fp_line
			(start 0.67945 -0.3048)
			(end 0.67945 0.3048)
			(stroke
				(width 0.1)
				(type default)
			)
			(layer "F.Fab")
		)
		(fp_line
			(start 0.12065 -0.3048)
			(end 0.67945 -0.3048)
			(stroke
				(width 0.1)
				(type default)
			)
			(layer "F.Fab")
		)
		(fp_line
			(start 0.12065 -0.2794)
			(end 0.12065 -0.3048)
			(stroke
				(width 0.1)
				(type default)
			)
			(layer "F.Fab")
		)
		(fp_line
			(start -0.12065 -0.2794)
			(end 0.12065 -0.2794)
			(stroke
				(width 0.1)
				(type default)
			)
			(layer "F.Fab")
		)
		(fp_line
			(start 0.120396 0.2794)
			(end -0.12065 0.2794)
			(stroke
				(width 0.1)
				(type default)
			)
			(layer "F.Fab")
		)
		(fp_line
			(start -0.12065 0.2794)
			(end -0.12065 0.3048)
			(stroke
				(width 0.1)
				(type default)
			)
			(layer "F.Fab")
		)
		(fp_line
			(start 0.67945 0.3048)
			(end 0.120396 0.3048)
			(stroke
				(width 0.1)
				(type default)
			)
			(layer "F.Fab")
		)
		(fp_line
			(start 0.120396 0.3048)
			(end 0.120396 0.2794)
			(stroke
				(width 0.1)
				(type default)
			)
			(layer "F.Fab")
		)
		(fp_line
			(start -0.12065 0.3048)
			(end -0.67945 0.3048)
			(stroke
				(width 0.1)
				(type default)
			)
			(layer "F.Fab")
		)
		(fp_line
			(start -0.67945 0.3048)
			(end -0.67945 -0.305054)
			(stroke
				(width 0.1)
				(type default)
			)
			(layer "F.Fab")
		)
		(pad "1" smd circle
			(at -0.40005 0 90)
			(size 0 0)
			(layers "F.Cu" "F.Mask" "F.Paste")
			(net "SGPIO_CLK_1")
		)
		(pad "2" smd circle
			(at 0.40005 0 90)
			(size 0 0)
			(layers "F.Cu" "F.Mask" "F.Paste")
			(net "SGPIO_BMC_M1_CLK")
		)
	)
)
